# TIMECARD (Time Appliance Project (Time Card)) — schematic netlist excerpt (pin names and nets, part order shuffled) for the footprints in the layout excerpt that follows; sources: Cadence DE-HDL packaged netlist, KiCad conversion of R4006-B0001-02_R01.brd

C195  CAPACITOR  10UF 25V 20%  pkg SMC_0805R_H057  page 30 : \1\ = XP1R8V_FPGA ; \2\ = SG

(kicad_pcb
	(version 20260206)
	(generator "pcbnew")
	(generator_version "10.0")
	(general
		(thickness 1.6)
		(legacy_teardrops no)
	)
	(paper "A4")
	(title_block
		(title "timecard-production-celestica-r4006 — R4006-B0001-02_R01.brd")
		(comment 1 "Time Appliance Project (Time Card) / footprints 246-246 of 1113")
	)
	(layers
		(0 "F.Cu" signal "TOP")
		(4 "In1.Cu" signal "L02_GND1")
		(6 "In2.Cu" signal "L03_SIG1")
		(8 "In3.Cu" signal "L04_GND2")
		(10 "In4.Cu" signal "L05_VCC1")
		(12 "In5.Cu" signal "L06_VCC2")
		(14 "In6.Cu" signal "L07_GND3")
		(16 "In7.Cu" signal "L08_SIG2")
		(18 "In8.Cu" signal "L09_GND4")
		(2 "B.Cu" signal "BOTTOM")
		(9 "F.Adhes" user "F.Adhesive")
		(11 "B.Adhes" user "B.Adhesive")
		(13 "F.Paste" user "Package Geometry/Pastemask Top")
		(15 "B.Paste" user "Package Geometry/Pastemask Bottom")
		(5 "F.SilkS" user "Ref Des/Silkscreen Top")
		(7 "B.SilkS" user "Ref Des/Silkscreen Bottom")
		(1 "F.Mask" user "Board Geometry/Soldermask Top")
		(3 "B.Mask" user "Board Geometry/Soldermask Bottom")
		(17 "Dwgs.User" user "User.Drawings")
		(19 "Cmts.User" user "User.Comments")
		(21 "Eco1.User" user "User.Eco1")
		(23 "Eco2.User" user "User.Eco2")
		(25 "Edge.Cuts" user "Board Geometry/Outline")
		(27 "Margin" user)
		(31 "F.CrtYd" user "Package Geometry/Place Bound Top")
		(29 "B.CrtYd" user "Package Geometry/Place Bound Bottom")
		(35 "F.Fab" user "Ref Des/Assembly Top")
		(33 "B.Fab" user "Ref Des/Assembly Bottom")
	)
	(footprint ""
		(layer "F.Cu")
		(at 131.953 -64.0334 180)
		(property "Reference" "C195"
			(at -0.381 -3.36677 0)
			(unlocked yes)
			(layer "F.SilkS")
			(effects
				(font
					(size 0.7874 0.5842)
					(thickness 0.1524)
				)
			)
		)
		(property "Value" "VAL*"
			(at 0.0762 3.134106 180)
			(unlocked yes)
			(layer "F.Fab")
			(hide yes)
			(effects
				(font
					(size 0.7874 0.5842)
					(thickness 0.1524)
				)
			)
		)
		(property "Tolerance" "TOL*"
			(at 0.0762 4.048506 180)
			(unlocked yes)
			(layer "Cmts.User")
			(hide yes)
			(effects
				(font
					(size 0.7874 0.5842)
					(thickness 0.1524)
				)
			)
		)
		(property "User Part Number" "PARTNUM*"
			(at 0.1016 5.013706 180)
			(unlocked yes)
			(layer "Cmts.User")
			(hide yes)
			(effects
				(font
					(size 0.7874 0.5842)
					(thickness 0.1524)
				)
			)
		)
		(property "Device Type" "CAPACITOR-G107-0F106-EM,10UF,2A"
			(at 0.0508 2.194306 180)
			(unlocked yes)
			(layer "F.Fab")
			(hide yes)
			(effects
				(font
					(size 0.7874 0.5842)
					(thickness 0.1524)
				)
			)
		)
		(duplicate_pad_numbers_are_jumpers no)
		(fp_line
			(start 1.5748 0.9398)
			(end 1.5748 -0.9398)
			(stroke
				(width 0.1)
				(type default)
			)
			(layer "F.SilkS")
		)
		(fp_line
			(start 1.5748 -0.9398)
			(end -1.5748 -0.9398)
			(stroke
				(width 0.1)
				(type default)
			)
			(layer "F.SilkS")
		)
		(fp_line
			(start -1.5748 0.9398)
			(end 1.5748 0.9398)
			(stroke
				(width 0.1)
				(type default)
			)
			(layer "F.SilkS")
		)
		(fp_line
			(start -1.5748 -0.9398)
			(end -1.5748 0.9398)
			(stroke
				(width 0.1)
				(type default)
			)
			(layer "F.SilkS")
		)
		(fp_rect
			(start -1.5748 0.9398)
			(end 1.5748 -0.9398)
			(stroke
				(width 0)
				(type default)
			)
			(fill no)
			(layer "F.CrtYd")
		)
		(fp_line
			(start 1.016 0.635)
			(end 1.016 -0.635)
			(stroke
				(width 0.1)
				(type default)
			)
			(layer "F.Fab")
		)
		(fp_line
			(start 1.016 -0.635)
			(end -1.016 -0.635)
			(stroke
				(width 0.1)
				(type default)
			)
			(layer "F.Fab")
		)
		(fp_line
			(start -1.016 0.635)
			(end 1.016 0.635)
			(stroke
				(width 0.1)
				(type default)
			)
			(layer "F.Fab")
		)
		(fp_line
			(start -1.016 -0.635)
			(end -1.016 0.635)
			(stroke
				(width 0.1)
				(type default)
			)
			(layer "F.Fab")
		)
		(pad "1" smd rect
			(at -0.8382 0 180)
			(size 0.9652 1.3716)
			(layers "F.Cu" "F.Mask" "F.Paste")
			(net "XP1R8V_FPGA")
		)
		(pad "2" smd rect
			(at 0.8382 0 180)
			(size 0.9652 1.3716)
			(layers "F.Cu" "F.Mask" "F.Paste")
			(net "SG")
		)
		(zone
			(layer "F.Cu")
			(hatch none 0.5)
			(connect_pads
				(clearance 0)
			)
			(min_thickness 0.25)
			(keepout
				(tracks allowed)
				(vias not_allowed)
				(pads allowed)
				(copperpour not_allowed)
				(footprints allowed)
			)
			(placement
				(enabled no)
				(sheetname "")
			)
			(fill
				(thermal_gap 0.5)
				(thermal_bridge_width 0.5)
				(island_removal_mode 0)
			)
			(polygon
				(pts
					(xy 132.1816 -64.6684) (xy 131.7244 -64.6684) (xy 131.7244 -63.3984) (xy 132.1816 -63.3984)
				)
			)
		)
	)
)
